(kicad_pcb
	(version 20241229)
	(generator "pcbnew")
	(generator_version "9.0")
	(general
		(thickness 1.61)
		(legacy_teardrops no)
	)
	(paper "A3")
	(title_block
		(title "SO-DIMM DDR5 Tester")
		(date "2025-11-26")
		(rev "1.3.0")
		(comment 9 "footprints 412-417 of 627")
	)
	(layers
		(0 "F.Cu" signal)
		(4 "In1.Cu" power)
		(6 "In2.Cu" mixed)
		(8 "In3.Cu" power)
		(10 "In4.Cu" mixed)
		(12 "In5.Cu" power)
		(14 "In6.Cu" mixed)
		(16 "In7.Cu" power)
		(18 "In8.Cu" power)
		(20 "In9.Cu" mixed)
		(22 "In10.Cu" power)
		(2 "B.Cu" signal)
		(9 "F.Adhes" user "F.Adhesive")
		(11 "B.Adhes" user "B.Adhesive")
		(13 "F.Paste" user)
		(15 "B.Paste" user)
		(5 "F.SilkS" user "F.Silkscreen")
		(7 "B.SilkS" user "B.Silkscreen")
		(1 "F.Mask" user)
		(3 "B.Mask" user)
		(17 "Dwgs.User" user "User.Drawings")
		(19 "Cmts.User" user "User.Comments")
		(21 "Eco1.User" user "User.Eco1")
		(23 "Eco2.User" user "User.Eco2")
		(25 "Edge.Cuts" user)
		(27 "Margin" user)
		(31 "F.CrtYd" user "F.Courtyard")
		(29 "B.CrtYd" user "B.Courtyard")
		(35 "F.Fab" user)
		(33 "B.Fab" user)
	)
	(footprint "antmicro-footprints:C_0402_1005Metric"
		(layer "B.Cu")
		(at 144.525501 204.800501 90)
		(descr "Capacitor SMD 0402")
		(tags "capacitor SMD 0402")
		(property "Reference" "C226"
			(at 0 0.699 270)
			(layer "B.SilkS")
			(hide yes)
			(effects
				(font
					(size 0.7 0.7)
					(thickness 0.15)
				)
				(justify left bottom mirror)
			)
		)
		(property "Value" "C_100n_0402"
			(at -1.022927 -2.155213 270)
			(layer "B.Fab")
			(effects
				(font
					(size 0.7 0.7)
					(thickness 0.15)
				)
				(justify left bottom mirror)
			)
		)
		(property "Datasheet" "https://www.murata.com/products/productdetail?partno=GRM155R61H104KE14%23"
			(at 0 0 90)
			(layer "F.Fab")
			(hide yes)
			(effects
				(font
					(size 1.27 1.27)
					(thickness 0.15)
				)
			)
		)
		(property "Author" "Antmicro"
			(at 349.326002 60.275 0)
			(layer "B.Fab")
			(hide yes)
			(effects
				(font
					(size 1 1)
					(thickness 0.15)
				)
				(justify mirror)
			)
		)
		(property "Dielectric" "X5R"
			(at 349.326002 60.275 0)
			(layer "B.Fab")
			(hide yes)
			(effects
				(font
					(size 1 1)
					(thickness 0.15)
				)
				(justify mirror)
			)
		)
		(property "License" "Apache-2.0"
			(at 349.326002 60.275 0)
			(layer "B.Fab")
			(hide yes)
			(effects
				(font
					(size 1 1)
					(thickness 0.15)
				)
				(justify mirror)
			)
		)
		(property "MPN" "GRM155R61H104KE14D"
			(at 349.326002 60.275 0)
			(layer "B.Fab")
			(hide yes)
			(effects
				(font
					(size 1 1)
					(thickness 0.15)
				)
				(justify mirror)
			)
		)
		(property "Manufacturer" "Murata"
			(at 349.326002 60.275 0)
			(layer "B.Fab")
			(hide yes)
			(effects
				(font
					(size 1 1)
					(thickness 0.15)
				)
				(justify mirror)
			)
		)
		(property "Val" "100n"
			(at 349.326002 60.275 0)
			(layer "B.Fab")
			(hide yes)
			(effects
				(font
					(size 1 1)
					(thickness 0.15)
				)
				(justify mirror)
			)
		)
		(property "Voltage" "50V"
			(at 349.326002 60.275 0)
			(layer "B.Fab")
			(hide yes)
			(effects
				(font
					(size 1 1)
					(thickness 0.15)
				)
				(justify mirror)
			)
		)
		(sheetname "/FPGA MGT Interface/")
		(sheetfile "fpga-mgt.kicad_sch")
		(attr smd)
		(fp_rect
			(start -0.9659 0.481258)
			(end 0.9649 -0.458742)
			(stroke
				(width 0.05)
				(type solid)
			)
			(fill no)
			(layer "B.CrtYd")
		)
		(fp_line
			(start 0.499 -0.248)
			(end -0.499 -0.248)
			(stroke
				(width 0.15)
				(type solid)
			)
			(layer "B.Fab")
		)
		(fp_line
			(start -0.499 -0.248)
			(end -0.499 0.25)
			(stroke
				(width 0.15)
				(type solid)
			)
			(layer "B.Fab")
		)
		(fp_line
			(start 0.499 0.25)
			(end 0.499 -0.248)
			(stroke
				(width 0.15)
				(type solid)
			)
			(layer "B.Fab")
		)
		(fp_line
			(start -0.499 0.25)
			(end 0.499 0.25)
			(stroke
				(width 0.15)
				(type solid)
			)
			(layer "B.Fab")
		)
		(pad "1" smd roundrect
			(at -0.484 0 90)
			(size 0.59 0.64)
			(layers "B.Cu" "B.Mask" "B.Paste")
			(roundrect_rratio 0.25)
			(net 16 "/FPGA MGT Interface/PCIE.TXD3_P")
			(pintype "passive")
		)
		(pad "2" smd roundrect
			(at 0.484 0 90)
			(size 0.59 0.64)
			(layers "B.Cu" "B.Mask" "B.Paste")
			(roundrect_rratio 0.25)
			(net 17 "/FPGA MGT Interface/GTX_TX0_P")
			(pintype "passive")
		)
	)
	(footprint "antmicro-footprints:C_0603_1608Metric"
		(layer "B.Cu")
		(at 142.175501 174.801)
		(descr "Capacitor SMD 0603")
		(tags "capacitor 0603")
		(property "Reference" "C11"
			(at 0 0.9 0)
			(layer "B.SilkS")
			(hide yes)
			(effects
				(font
					(size 0.7 0.7)
					(thickness 0.15)
				)
				(justify right bottom mirror)
			)
		)
		(property "Value" "C_47u_0603"
			(at 0 -1.6 0)
			(layer "B.Fab")
			(effects
				(font
					(size 0.7 0.7)
					(thickness 0.15)
				)
				(justify right bottom mirror)
			)
		)
		(property "Datasheet" "https://www.murata.com/products/productdetail?partno=GRM188R60J476ME15%23"
			(at 0 0 0)
			(layer "F.Fab")
			(hide yes)
			(effects
				(font
					(size 1.27 1.27)
					(thickness 0.15)
				)
			)
		)
		(property "Author" "Antmicro"
			(at 0 0 0)
			(layer "B.Fab")
			(hide yes)
			(effects
				(font
					(size 1 1)
					(thickness 0.15)
				)
				(justify mirror)
			)
		)
		(property "Dielectric" ""
			(at 0 0 0)
			(layer "B.Fab")
			(hide yes)
			(effects
				(font
					(size 1 1)
					(thickness 0.15)
				)
				(justify mirror)
			)
		)
		(property "License" "Apache-2.0"
			(at 0 0 0)
			(layer "B.Fab")
			(hide yes)
			(effects
				(font
					(size 1 1)
					(thickness 0.15)
				)
				(justify mirror)
			)
		)
		(property "MPN" "GRM188R60J476ME15D"
			(at 0 0 0)
			(layer "B.Fab")
			(hide yes)
			(effects
				(font
					(size 1 1)
					(thickness 0.15)
				)
				(justify mirror)
			)
		)
		(property "Manufacturer" "Murata"
			(at 0 0 0)
			(layer "B.Fab")
			(hide yes)
			(effects
				(font
					(size 1 1)
					(thickness 0.15)
				)
				(justify mirror)
			)
		)
		(property "Val" "47u"
			(at 0 0 0)
			(layer "B.Fab")
			(hide yes)
			(effects
				(font
					(size 1 1)
					(thickness 0.15)
				)
				(justify mirror)
			)
		)
		(property "Voltage" ""
			(at 0 0 0)
			(layer "B.Fab")
			(hide yes)
			(effects
				(font
					(size 1 1)
					(thickness 0.15)
				)
				(justify mirror)
			)
		)
		(sheetname "/FPGA power/")
		(sheetfile "fpga-power.kicad_sch")
		(attr smd)
		(fp_line
			(start -0.3 -0.3)
			(end 0.3 -0.3)
			(stroke
				(width 0.15)
				(type solid)
			)
			(layer "B.SilkS")
		)
		(fp_line
			(start -0.3 0.3)
			(end 0.3 0.3)
			(stroke
				(width 0.15)
				(type solid)
			)
			(layer "B.SilkS")
		)
		(fp_rect
			(start -1.24 0.7)
			(end 1.24 -0.7)
			(stroke
				(width 0.05)
				(type solid)
			)
			(fill no)
			(layer "B.CrtYd")
		)
		(fp_rect
			(start -0.8 0.4)
			(end 0.8 -0.4)
			(stroke
				(width 0.15)
				(type solid)
			)
			(fill no)
			(layer "B.Fab")
		)
		(pad "1" smd roundrect
			(at -0.7 0)
			(size 0.6 0.8)
			(layers "B.Cu" "B.Mask" "B.Paste")
			(roundrect_rratio 0.2)
			(net 188 "+1V8")
			(pintype "passive")
		)
		(pad "2" smd roundrect
			(at 0.7 0)
			(size 0.6 0.8)
			(layers "B.Cu" "B.Mask" "B.Paste")
			(roundrect_rratio 0.2)
			(net 1 "GND")
			(pintype "passive")
		)
	)
	(footprint "antmicro-footprints:TP_SMD_1mm"
		(layer "B.Cu")
		(at 198.4 161.6)
		(property "Reference" "TP71"
			(at 2.55 1.45 180)
			(layer "B.SilkS")
			(effects
				(font
					(size 0.7 0.7)
					(thickness 0.15)
				)
				(justify left bottom mirror)
			)
		)
		(property "Value" "TP_1mm_SMD"
			(at 0 -1.4 180)
			(layer "B.Fab")
			(effects
				(font
					(size 0.7 0.7)
					(thickness 0.15)
				)
				(justify left bottom mirror)
			)
		)
		(property "MPN" ""
			(at 0 0 180)
			(unlocked yes)
			(layer "B.Fab")
			(hide yes)
			(effects
				(font
					(size 1 1)
					(thickness 0.15)
				)
				(justify mirror)
			)
		)
		(property "Manufacturer" ""
			(at 0 0 180)
			(unlocked yes)
			(layer "B.Fab")
			(hide yes)
			(effects
				(font
					(size 1 1)
					(thickness 0.15)
				)
				(justify mirror)
			)
		)
		(property "Author" "Antmicro"
			(at 0 0 180)
			(unlocked yes)
			(layer "B.Fab")
			(hide yes)
			(effects
				(font
					(size 1 1)
					(thickness 0.15)
				)
				(justify mirror)
			)
		)
		(property "License" "Apache-2.0"
			(at 0 0 180)
			(unlocked yes)
			(layer "B.Fab")
			(hide yes)
			(effects
				(font
					(size 1 1)
					(thickness 0.15)
				)
				(justify mirror)
			)
		)
		(sheetname "/Supply/")
		(sheetfile "supply.kicad_sch")
		(attr exclude_from_pos_files)
		(fp_circle
			(center 0 0)
			(end 0.6 0)
			(stroke
				(width 0.05)
				(type default)
			)
			(fill no)
			(layer "B.CrtYd")
		)
		(fp_text user "Author: Antmicro"
			(at -0.5 -4 180)
			(layer "B.Fab")
			(effects
				(font
					(size 0.7 0.7)
					(thickness 0.15)
				)
				(justify left bottom mirror)
			)
		)
		(fp_text user "${REFERENCE}"
			(at -0.5 -2.8 180)
			(layer "B.Fab")
			(effects
				(font
					(size 0.7 0.7)
					(thickness 0.15)
				)
				(justify left bottom mirror)
			)
		)
		(fp_text user "License: Apache-2.0"
			(at -0.5 -5.2 180)
			(layer "B.Fab")
			(effects
				(font
					(size 0.7 0.7)
					(thickness 0.15)
				)
				(justify left bottom mirror)
			)
		)
		(pad "1" smd circle
			(at 0 0)
			(size 1 1)
			(layers "B.Cu" "B.Mask")
			(net 285 "/Supply/QDCDC2_SCL")
			(pinfunction "1")
			(pintype "passive")
		)
	)
	(footprint "antmicro-footprints:C_0402_1005Metric"
		(layer "B.Cu")
		(at 139.875001 171.3025)
		(descr "Capacitor SMD 0402 (1005 Metric), square (rectangular) end terminal, IPC_7351 nominal, (Body size source: IPC-SM-782 page 76, https://www.pcb-3d.com/wordpress/wp-content/uploads/ipc-sm-782a_amendment_1_and_2.pdf)")
		(tags "capacitor 0402")
		(property "Reference" "C83"
			(at 0 1.17 180)
			(layer "B.SilkS")
			(hide yes)
			(effects
				(font
					(size 0.7 0.7)
					(thickness 0.15)
				)
				(justify left bottom mirror)
			)
		)
		(property "Value" "C_100n_0402"
			(at 0 -1.169 180)
			(layer "B.Fab")
			(effects
				(font
					(size 0.7 0.7)
					(thickness 0.15)
				)
				(justify left bottom mirror)
			)
		)
		(property "Datasheet" "https://www.murata.com/products/productdetail?partno=GRM155R61H104KE14%23"
			(at 0 0 0)
			(layer "F.Fab")
			(hide yes)
			(effects
				(font
					(size 1.27 1.27)
					(thickness 0.15)
				)
			)
		)
		(property "Author" "Antmicro"
			(at 0 0 0)
			(layer "B.Fab")
			(hide yes)
			(effects
				(font
					(size 1 1)
					(thickness 0.15)
				)
				(justify mirror)
			)
		)
		(property "Dielectric" "X5R"
			(at 0 0 0)
			(layer "B.Fab")
			(hide yes)
			(effects
				(font
					(size 1 1)
					(thickness 0.15)
				)
				(justify mirror)
			)
		)
		(property "License" "Apache-2.0"
			(at 0 0 0)
			(layer "B.Fab")
			(hide yes)
			(effects
				(font
					(size 1 1)
					(thickness 0.15)
				)
				(justify mirror)
			)
		)
		(property "MPN" "GRM155R61H104KE14D"
			(at 0 0 0)
			(layer "B.Fab")
			(hide yes)
			(effects
				(font
					(size 1 1)
					(thickness 0.15)
				)
				(justify mirror)
			)
		)
		(property "Manufacturer" "Murata"
			(at 0 0 0)
			(layer "B.Fab")
			(hide yes)
			(effects
				(font
					(size 1 1)
					(thickness 0.15)
				)
				(justify mirror)
			)
		)
		(property "Val" "100n"
			(at 0 0 0)
			(layer "B.Fab")
			(hide yes)
			(effects
				(font
					(size 1 1)
					(thickness 0.15)
				)
				(justify mirror)
			)
		)
		(property "Voltage" "50V"
			(at 0 0 0)
			(layer "B.Fab")
			(hide yes)
			(effects
				(font
					(size 1 1)
					(thickness 0.15)
				)
				(justify mirror)
			)
		)
		(sheetname "/FPGA power/")
		(sheetfile "fpga-power.kicad_sch")
		(attr smd)
		(fp_rect
			(start -0.9656 0.4572)
			(end 0.9652 -0.4828)
			(stroke
				(width 0.05)
				(type solid)
			)
			(fill no)
			(layer "B.CrtYd")
		)
		(fp_line
			(start -0.5 -0.248)
			(end -0.5 0.25)
			(stroke
				(width 0.15)
				(type solid)
			)
			(layer "B.Fab")
		)
		(fp_line
			(start -0.5 0.25)
			(end 0.498 0.25)
			(stroke
				(width 0.15)
				(type solid)
			)
			(layer "B.Fab")
		)
		(fp_line
			(start 0.498 -0.248)
			(end -0.5 -0.248)
			(stroke
				(width 0.15)
				(type solid)
			)
			(layer "B.Fab")
		)
		(fp_line
			(start 0.498 0.25)
			(end 0.498 -0.248)
			(stroke
				(width 0.15)
				(type solid)
			)
			(layer "B.Fab")
		)
		(pad "1" smd roundrect
			(at -0.5 0 270)
			(size 0.6 0.6)
			(layers "B.Cu" "B.Mask" "B.Paste")
			(roundrect_rratio 0.25)
			(net 1 "GND")
			(pintype "passive")
		)
		(pad "2" smd roundrect
			(at 0.498 0)
			(size 0.6 0.6)
			(layers "B.Cu" "B.Mask" "B.Paste")
			(roundrect_rratio 0.25)
			(net 227 "+1V0")
			(pintype "passive")
		)
	)
	(footprint "antmicro-footprints:C_0402_1005Metric"
		(layer "B.Cu")
		(at 156.500501 175.276)
		(descr "Capacitor SMD 0402")
		(tags "capacitor SMD 0402")
		(property "Reference" "C198"
			(at 0 0.699 180)
			(layer "B.SilkS")
			(hide yes)
			(effects
				(font
					(size 0.7 0.7)
					(thickness 0.15)
				)
				(justify left bottom mirror)
			)
		)
		(property "Value" "C_1u_0402"
			(at -1.022927 -2.155213 180)
			(layer "B.Fab")
			(effects
				(font
					(size 0.7 0.7)
					(thickness 0.15)
				)
				(justify left bottom mirror)
			)
		)
		(property "Datasheet" "https://product.tdk.com/en/search/capacitor/ceramic/mlcc/info?part_no=C1005X6S1A105K050BC"
			(at 0 0 0)
			(layer "F.Fab")
			(hide yes)
			(effects
				(font
					(size 1.27 1.27)
					(thickness 0.15)
				)
			)
		)
		(property "Author" "Antmicro"
			(at 0 0 0)
			(layer "B.Fab")
			(hide yes)
			(effects
				(font
					(size 1 1)
					(thickness 0.15)
				)
				(justify mirror)
			)
		)
		(property "Dielectric" ""
			(at 0 0 0)
			(layer "B.Fab")
			(hide yes)
			(effects
				(font
					(size 1 1)
					(thickness 0.15)
				)
				(justify mirror)
			)
		)
		(property "License" "Apache-2.0"
			(at 0 0 0)
			(layer "B.Fab")
			(hide yes)
			(effects
				(font
					(size 1 1)
					(thickness 0.15)
				)
				(justify mirror)
			)
		)
		(property "MPN" "C1005X6S1A105K050BC"
			(at 0 0 0)
			(layer "B.Fab")
			(hide yes)
			(effects
				(font
					(size 1 1)
					(thickness 0.15)
				)
				(justify mirror)
			)
		)
		(property "Manufacturer" "TDK"
			(at 0 0 0)
			(layer "B.Fab")
			(hide yes)
			(effects
				(font
					(size 1 1)
					(thickness 0.15)
				)
				(justify mirror)
			)
		)
		(property "Val" "1u"
			(at 0 0 0)
			(layer "B.Fab")
			(hide yes)
			(effects
				(font
					(size 1 1)
					(thickness 0.15)
				)
				(justify mirror)
			)
		)
		(property "Voltage" ""
			(at 0 0 0)
			(layer "B.Fab")
			(hide yes)
			(effects
				(font
					(size 1 1)
					(thickness 0.15)
				)
				(justify mirror)
			)
		)
		(sheetname "/Supply/")
		(sheetfile "supply.kicad_sch")
		(attr smd)
		(fp_rect
			(start -0.9659 0.481258)
			(end 0.9649 -0.458742)
			(stroke
				(width 0.05)
				(type solid)
			)
			(fill no)
			(layer "B.CrtYd")
		)
		(fp_line
			(start -0.499 -0.248)
			(end -0.499 0.25)
			(stroke
				(width 0.15)
				(type solid)
			)
			(layer "B.Fab")
		)
		(fp_line
			(start -0.499 0.25)
			(end 0.499 0.25)
			(stroke
				(width 0.15)
				(type solid)
			)
			(layer "B.Fab")
		)
		(fp_line
			(start 0.499 -0.248)
			(end -0.499 -0.248)
			(stroke
				(width 0.15)
				(type solid)
			)
			(layer "B.Fab")
		)
		(fp_line
			(start 0.499 0.25)
			(end 0.499 -0.248)
			(stroke
				(width 0.15)
				(type solid)
			)
			(layer "B.Fab")
		)
		(pad "1" smd roundrect
			(at -0.484 0)
			(size 0.59 0.64)
			(layers "B.Cu" "B.Mask" "B.Paste")
			(roundrect_rratio 0.25)
			(net 1 "GND")
			(pintype "passive")
		)
		(pad "2" smd roundrect
			(at 0.484 0)
			(size 0.59 0.64)
			(layers "B.Cu" "B.Mask" "B.Paste")
			(roundrect_rratio 0.25)
			(net 201 "+5V")
			(pintype "passive")
		)
	)
	(footprint "antmicro-footprints:C_0402_1005Metric"
		(layer "B.Cu")
		(at 117.150501 205.426 180)
		(descr "Capacitor SMD 0402")
		(tags "capacitor SMD 0402")
		(property "Reference" "C170"
			(at 0 0.699 0)
			(layer "B.SilkS")
			(hide yes)
			(effects
				(font
					(size 0.7 0.7)
					(thickness 0.15)
				)
				(justify left bottom mirror)
			)
		)
		(property "Value" "C_100n_0402"
			(at -1.022927 -2.155213 0)
			(layer "B.Fab")
			(effects
				(font
					(size 0.7 0.7)
					(thickness 0.15)
				)
				(justify left bottom mirror)
			)
		)
		(property "Datasheet" "https://www.murata.com/products/productdetail?partno=GRM155R61H104KE14%23"
			(at 0 0 180)
			(layer "F.Fab")
			(hide yes)
			(effects
				(font
					(size 1.27 1.27)
					(thickness 0.15)
				)
			)
		)
		(property "Author" "Antmicro"
			(at 234.301002 410.852 0)
			(layer "B.Fab")
			(hide yes)
			(effects
				(font
					(size 1 1)
					(thickness 0.15)
				)
				(justify mirror)
			)
		)
		(property "Dielectric" "X5R"
			(at 234.301002 410.852 0)
			(layer "B.Fab")
			(hide yes)
			(effects
				(font
					(size 1 1)
					(thickness 0.15)
				)
				(justify mirror)
			)
		)
		(property "License" "Apache-2.0"
			(at 234.301002 410.852 0)
			(layer "B.Fab")
			(hide yes)
			(effects
				(font
					(size 1 1)
					(thickness 0.15)
				)
				(justify mirror)
			)
		)
		(property "MPN" "GRM155R61H104KE14D"
			(at 234.301002 410.852 0)
			(layer "B.Fab")
			(hide yes)
			(effects
				(font
					(size 1 1)
					(thickness 0.15)
				)
				(justify mirror)
			)
		)
		(property "Manufacturer" "Murata"
			(at 234.301002 410.852 0)
			(layer "B.Fab")
			(hide yes)
			(effects
				(font
					(size 1 1)
					(thickness 0.15)
				)
				(justify mirror)
			)
		)
		(property "Val" "100n"
			(at 234.301002 410.852 0)
			(layer "B.Fab")
			(hide yes)
			(effects
				(font
					(size 1 1)
					(thickness 0.15)
				)
				(justify mirror)
			)
		)
		(property "Voltage" "50V"
			(at 234.301002 410.852 0)
			(layer "B.Fab")
			(hide yes)
			(effects
				(font
					(size 1 1)
					(thickness 0.15)
				)
				(justify mirror)
			)
		)
		(sheetname "/Supply/")
		(sheetfile "supply.kicad_sch")
		(attr smd)
		(fp_rect
			(start -0.9659 0.481258)
			(end 0.9649 -0.458742)
			(stroke
				(width 0.05)
				(type solid)
			)
			(fill no)
			(layer "B.CrtYd")
		)
		(fp_line
			(start 0.499 0.25)
			(end 0.499 -0.248)
			(stroke
				(width 0.15)
				(type solid)
			)
			(layer "B.Fab")
		)
		(fp_line
			(start 0.499 -0.248)
			(end -0.499 -0.248)
			(stroke
				(width 0.15)
				(type solid)
			)
			(layer "B.Fab")
		)
		(fp_line
			(start -0.499 0.25)
			(end 0.499 0.25)
			(stroke
				(width 0.15)
				(type solid)
			)
			(layer "B.Fab")
		)
		(fp_line
			(start -0.499 -0.248)
			(end -0.499 0.25)
			(stroke
				(width 0.15)
				(type solid)
			)
			(layer "B.Fab")
		)
		(pad "1" smd roundrect
			(at -0.484 0 180)
			(size 0.59 0.64)
			(layers "B.Cu" "B.Mask" "B.Paste")
			(roundrect_rratio 0.25)
			(net 1 "GND")
			(pintype "passive")
		)
		(pad "2" smd roundrect
			(at 0.484 0 180)
			(size 0.59 0.64)
			(layers "B.Cu" "B.Mask" "B.Paste")
			(roundrect_rratio 0.25)
			(net 11 "+12V")
			(pintype "passive")
		)
	)
)
